FILE_TYPE = CONNECTIVITY;
{Allegro Design Entry HDL 17.2-2016 S081 (4005846) 1/11/2022}
"PAGE_NUMBER" = 45;
0"NC";
1"PVNN_TERM_CPU1\g";
2"TP_H_CPU1_PMSYNC_PCH_INTRP_R";
3"CPU1_RSVD<107>";
4"PU_TAP_ODT_CPU1_EN";
5"SMB_S3M_CPU1_PIROM_3V3AUX_SCL";
6"PU_PIROM_CPU1_ADDR0";
7"PD_PIROM_CPU1_ADDR1";
8"PD_PIROM_CPU1_ADDR2";
9"SMB_PEHPCPU1_GTL_SCL";
10"SMB_PEHPCPU1_GTL_SDA";
11"FM_PEHPCPU1_ALERT_N";
12"PWRGD_DRAMPWRGD_CPU1_AB_LVC1_R";
13"PWRGD_DRAMPWRGD_CPU1_CD_LVC1_R";
14"PWRGD_DRAMPWRGD_CPU1_EF_LVC1_R";
15"PWRGD_DRAMPWRGD_CPU1_GH_LVC1_R";
16"PD_CPU1_ENH_MCECC_DIS";
17"SMB_S3M_CPU1_PIROM_3V3AUX_SCL_R1";
18"SMB_S3M_CPU1_PIROM_3V3AUX_SDA_R1";
19"PU_PIROM_CPU1_SM_WP";
20"TP_H_SBLINK7_CPU1_PMDOWN";
21"TP_H_SBLINK6_CPU1_PMDOWN";
22"TP_H_SBLINK5_CPU1_PMDOWN";
23"TP_H_SBLINK4_CPU1_PMDOWN";
24"TP_H_SBLINK3_CPU1_PMDOWN";
25"TP_H_SBLINK2_CPU1_PMDOWN";
26"H_CPU0_PMSYNC_CPU1";
27"TP_H_CPU1_PMDOWN_PCH_R";
28"TP_H_SBLINK7_CPU1_PMSYNC";
29"TP_H_SBLINK6_CPU1_PMSYNC";
30"TP_H_SBLINK5_CPU1_PMSYNC";
31"TP_H_SBLINK4_CPU1_PMSYNC";
32"TP_H_SBLINK3_CPU1_PMSYNC";
33"TP_H_SBLINK2_CPU1_PMSYNC";
34"H_CPU0_PMDOWN_CPU1";
35"PWRGD_CPU1_LVC1";
36"RST_CPU1_LVC1_N";
37"FM_CPU1_SKTOCC_LVT3_N";
38"H_CPU1_THERMTRIP_LVC1_R_N";
39"TP_EV_CPU1_EXT_BGREF";
40"SVID_DIO1_CPU1";
41"SVID_DIO0_CPU1";
42"SVID_CLK1_CPU1";
43"SVID_CLK0_CPU1";
44"SVID_ALERT1_CPU1_N";
45"SVID_ALERT0_CPU1_N";
46"CPU1_RSVD<98>";
47"CPU1_RSVD<65>";
48"CPU1_RSVD<64>";
49"CPU1_RSVD<6>";
50"CPU1_RSVD<54>";
51"CPU1_RSVD<4>";
52"CPU1_RSVD<27>";
53"CPU1_RSVD<25>";
54"CPU1_RSVD<15>";
55"CPU1_RSVD<144>";
56"CPU1_RSVD<140>";
57"CPU1_RSVD<139>";
58"CPU1_RSVD<135>";
59"CPU1_RSVD<126>";
60"CPU1_RSVD<120>";
61"CPU1_RSVD<115>";
62"CPU1_RSVD<110>";
63"H_CPU1_PROCHOT_LVC1_N";
64"H_CPU1_PM_FAST_WAKE_N";
65"H_CPU1_NMI_LVC1_N";
66"H_CPU1_MEMTRIP_LVC1_R_N";
67"H_CPU1_MEMHOT_OUT_LVC1_R_N";
68"H_CPU1_MEMHOT_IN_LVC1_N";
69"FM_CPU_FBRK_DEBUG_R_N";
70"H_CPU1_ERR0_LVC1_R_N";
71"H_CPU1_ERR1_LVC1_R_N";
72"H_CPU1_ERR2_LVC1_R_N";
73"H_CPU1_CATERR_LVC1_R_N";
74"SVID_DIO0_CPU1_R"CDS_PHYS_NET_NAME"SVID_DIO0_CPU0_R";
75"SVID_ALERT0_CPU1_R_N"$PHYS_NET_NAME"SVID_ALERT0_CPU0_R_N"CDS_PHYS_NET_NAME"SVID_ALERT0_CPU0_R_N";
76"SVID_DIO1_CPU1_R"CDS_PHYS_NET_NAME"SVID_DIO1_CPU0_R";
77"SVID_CLK1_CPU1_R";
78"SVID_ALERT1_CPU1_R_N";
79"SMB_S3M_CPU1_PIROM_3V3AUX_SDA";
80"SVID_ALERT1_CPU1_R_N"CDS_PHYS_NET_NAME"SVID_CLK1_CPU0_R";
81"SVID_ALERT0_CPU1_R_N";
82"SVID_CLK0_CPU1_R";
83"SVID_DIO0_CPU1_R";
84"SVID_DIO1_CPU1_R";
%"SOCKET4677_AZIF0045P001C01CS"
"2","(-5750,-1925)","0","pure_quanta","I29";
;
PART_NUMBER"DGA^7000023"
PART_TYPE"SMLF"
MATERIAL"IO"
VALUE"SOCKET4677_AZIF0045-P001C01CS"
$LOCATION"U1"
CDS_LIB"pure_quanta"
NEEDS_NO_SIZE"TRUE"
CDS_LMAN_SYM_OUTLINE"-1100,1400,1050,-1400"
CDS_LOCATION"U1"
$SEC"2"
CDS_SEC"2";
"THERMTRIP_N \B"
$PN"BL62"38;
"RSVD19"
$PN"AV59"39;
"TAP_ODT_EN"
$PN"AY20"4;
"SVIDDATA1"
$PN"BL25"40;
"SVIDDATA0"
$PN"BD26"41;
"SVIDCLK1"
$PN"BF26"42;
"SVIDCLK0"
$PN"BH26"43;
"SVIDALERT1_N \B"
$PN"BJ25"44;
"SVIDALERT0_N \B"
$PN"BK26"45;
"SKTOCC_N \B"
$PN"CG66"37;
"RSVD104"
$PN"CJ62"46;
"RSVD70"
$PN"BP69"47;
"RSVD69"
$PN"BP67"48;
"RSVD6"
$PN"AU25"49;
"RSVD59"
$PN"BJ70"50;
"RSVD4"
$PN"AT24"51;
"RSVD29"
$PN"AY65"52;
"RSVD27"
$PN"AY26"53;
"RSVD15"
$PN"AV26"54;
"RSVD150"
$PN"CW68"55;
"RSVD146"
$PN"CW25"56;
"RSVD145"
$PN"CW23"57;
"RSVD141"
$PN"CV24"58;
"RSVD132"
$PN"CR23"59;
"RSVD126"
$PN"CN62"60;
"RSVD121"
$PN"CM63"61;
"RSVD116"
$PN"CL64"62;
"RSVD113"
$PN"CL21"3;
"RESET_N \B"
$PN"BH61"36;
"PWRGOOD"
$PN"AV20"35;
"PROCHOT_N \B"
$PN"AU19"63;
"PMSYNC_PCH"
$PN"DA39"2;
"PMSYNC0"
$PN"CN25"34;
"PMSYNC1"
$PN"CL25"33;
"PMSYNC2"
$PN"CH26"32;
"PMSYNC3"
$PN"CE25"31;
"PMSYNC4"
$PN"CR19"30;
"PMSYNC5"
$PN"CH24"29;
"PMSYNC6"
$PN"CF24"28;
"PMFAST_WAKE_N \B"
$PN"CP20"64;
"PMDOWN_PCH"
$PN"CY40"27;
"PMDOWN0"
$PN"CW39"26;
"PMDOWN1"
$PN"CP26"25;
"PMDOWN2"
$PN"CM26"24;
"PMDOWN3"
$PN"CD24"23;
"PMDOWN4"
$PN"CV18"22;
"PMDOWN5"
$PN"CE23"21;
"PMDOWN6"
$PN"CC25"20;
"PIROM_SM_WP"
$PN"CR72"19;
"PIROM_SDA"
$PN"CM71"18;
"PIROM_SCL"
$PN"CU70"17;
"PIROM_AD0"
$PN"CR70"6;
"PIROM_AD1"
$PN"CT71"7;
"PIROM_AD2"
$PN"CP71"8;
"NMI"
$PN"AV18"65;
"MEMTRIP_N \B"
$PN"AV24"66;
"MEMHOT_OUT_N \B"
$PN"CF26"67;
"MEMHOT_IN_N \B"
$PN"AU21"68;
"FBRK_N \B"
$PN"AV57"69;
"ERROR_N0 \B"
$PN"BF22"70;
"ERROR_N1 \B"
$PN"AY22"71;
"ERROR_N2 \B"
$PN"BD22"72;
"RSVD96"
$PN"CH22"16;
"DDR67_DRAM_PWR_OK"
$PN"CW45"15;
"DDR45_DRAM_PWR_OK"
$PN"CY44"14;
"DDR23_DRAM_PWR_OK"
$PN"F47"13;
"DDR01_DRAM_PWR_OK"
$PN"A43"12;
"CXPSMBUS_ALERT_N \B"
$PN"BV26"11;
"CXPSMBUSSDA"
$PN"BY26"10;
"CXPSMBUSSCL"
$PN"CA25"9;
"CATERR_N \B"
$PN"BP24"73;
%"Q_RES"
"1","(-3400,-875)","0","pure_quanta","I51";
;
PART_NUMBER"CS00002JB13"
VALUE"0"
PACK_TYPE"0402LF"
TOLERANCE"5%"
$LOCATION"R58"
CDS_LIB"pure_quanta"
MATERIAL"CHIP"
WATTAGE"1/16W"
$LOCATION"R58"
CDS_LOCATION"R58"
$SEC"1"
CDS_SEC"1";
"B"
$PN"2"84;
"A"
$PN"1"40;
%"Q_RES"
"1","(-3400,-925)","0","pure_quanta","I52";
;
PART_NUMBER"CS00002JB13"
VALUE"0"
TOLERANCE"5%"
PACK_TYPE"0402LF"
$LOCATION"R59"
CDS_LIB"pure_quanta"
WATTAGE"1/16W"
MATERIAL"CHIP"
$LOCATION"R59"
CDS_LOCATION"R59"
$SEC"1"
CDS_SEC"1";
"B"
$PN"2"77;
"A"
$PN"1"42;
%"Q_RES"
"1","(-3400,-975)","0","pure_quanta","I53";
;
PART_NUMBER"CS12002FB06"
VALUE"200"
TOLERANCE"1%"
MATERIAL"CHIP"
WATTAGE"1/16W"
PACK_TYPE"0402LF"
$LOCATION"R60"
CDS_LIB"pure_quanta"
$LOCATION"R60"
CDS_LOCATION"R60"
$SEC"1"
CDS_SEC"1";
"B"
$PN"2"78;
"A"
$PN"1"44;
%"Q_RES"
"1","(-3400,-675)","0","pure_quanta","I54";
;
PART_NUMBER"CS00002JB13"
VALUE"0"
TOLERANCE"5%"
MATERIAL"CHIP"
WATTAGE"1/16W"
PACK_TYPE"0402LF"
$LOCATION"R55"
CDS_LIB"pure_quanta"
$LOCATION"R55"
CDS_LOCATION"R55"
$SEC"1"
CDS_SEC"1";
"B"
$PN"2"83;
"A"
$PN"1"41;
%"Q_RES"
"1","(-3400,-725)","0","pure_quanta","I55";
;
PART_NUMBER"CS00002JB13"
VALUE"0"
TOLERANCE"5%"
PACK_TYPE"0402LF"
$LOCATION"R56"
CDS_LIB"pure_quanta"
WATTAGE"1/16W"
MATERIAL"CHIP"
$LOCATION"R56"
CDS_LOCATION"R56"
$SEC"1"
CDS_SEC"1";
"B"
$PN"2"82;
"A"
$PN"1"43;
%"Q_RES"
"1","(-3400,-775)","0","pure_quanta","I56";
;
PART_NUMBER"CS12002FB06"
VALUE"200"
TOLERANCE"1%"
WATTAGE"1/16W"
MATERIAL"CHIP"
PACK_TYPE"0402LF"
$LOCATION"R57"
CDS_LIB"pure_quanta"
$LOCATION"R57"
CDS_LOCATION"R57"
$SEC"1"
CDS_SEC"1";
"B"
$PN"2"81;
"A"
$PN"1"45;
%"Q_RES"
"1","(-3075,-4925)","0","pure_quanta","I69";
;
PART_NUMBER"CS11002FB07"
MATERIAL"CHIP"
PACK_TYPE"0402LF"
TOLERANCE"1%"
VALUE"100"
WATTAGE"1/16W"
$LOCATION"R559"
CDS_LIB"pure_quanta"
CDS_LOCATION"R559"
$SEC"1"
CDS_SEC"1";
"B"
$PN"2"1;
"A"
$PN"1"76;
%"Q_RES"
"1","(-3075,-5125)","0","pure_quanta","I70";
;
PART_NUMBER"CS04992FB07"
WATTAGE"1/16W"
PACK_TYPE"0402LF"
TOLERANCE"1%"
MATERIAL"CHIP"
VALUE"49.9"
$LOCATION"R560"
CDS_LIB"pure_quanta"
CDS_LOCATION"R560"
$SEC"1"
CDS_SEC"1";
"B"
$PN"2"1;
"A"
$PN"1"80;
%"Q_RES"
"1","(-3075,-4725)","0","pure_quanta","I73";
;
PART_NUMBER"CS04992FB07"
TOLERANCE"1%"
MATERIAL"CHIP"
PACK_TYPE"0402LF"
WATTAGE"1/16W"
VALUE"49.9"
$LOCATION"R558"
CDS_LIB"pure_quanta"
CDS_LOCATION"R558"
$SEC"1"
CDS_SEC"1";
"B"
$PN"2"1;
"A"
$PN"1"75;
%"Q_RES"
"1","(-3075,-4525)","0","pure_quanta","I74";
;
PART_NUMBER"CS11002FB07"
MATERIAL"CHIP"
TOLERANCE"1%"
PACK_TYPE"0402LF"
WATTAGE"1/16W"
VALUE"100"
$LOCATION"R557"
CDS_LIB"pure_quanta"
CDS_LOCATION"R557"
$SEC"1"
CDS_SEC"1";
"B"
$PN"2"1;
"A"
$PN"1"74;
%"UNIVERSAL_POWER"
"1","(-2525,-4300)","0","logical_power","I75";
;
HDL_POWER"PVNN_TERM_CPU1"
CDS_LIB"logical_power";
"A"1;
%"Q_RES"
"1","(-8475,-875)","0","pure_quanta","I81";
;
PART_NUMBER"CS03322FB03"
PACK_TYPE"0402LF"
TOLERANCE"1%"
MATERIAL"CHIP"
WATTAGE"1/16W"
VALUE"33.2"
$LOCATION"R1934"
CDS_LIB"pure_quanta"
CDS_LOCATION"R1934"
$SEC"1"
CDS_SEC"1";
"B"
$PN"2"17;
"A"
$PN"1"5;
%"Q_RES"
"1","(-8475,-925)","0","pure_quanta","I82";
;
PART_NUMBER"CS03322FB03"
MATERIAL"CHIP"
TOLERANCE"1%"
VALUE"33.2"
$LOCATION"R1935"
WATTAGE"1/16W"
PACK_TYPE"0402LF"
CDS_LIB"pure_quanta"
CDS_LOCATION"R1935"
$SEC"1"
CDS_SEC"1";
"B"
$PN"2"18;
"A"
$PN"1"79;
END.
